# TIMECARD (Time Appliance Project (Time Card)) — schematic parts with pin connectivity, parts 427–576 of 1119; source: Cadence DE-HDL packaged netlist (pstxprt.dat, pstxnet.dat, pstchip.dat)

R15  RESISTOR  10KOHM 1%  pkg SMC_0402R_H016  page 27 : 1 = XP12R0V ; 2 = XP12R0V_A_FLTB
R16  RESISTOR  3.92KOHM 1%  pkg SMC_0402R  page 27 : 1 = XP12R0V_A_FLTB ; 2 = SG
R17  RESISTOR  20OHM 1%  pkg SMC_0402R_H016  page 28 : 1 = XP3R3V ; 2 = UNNAMED_517_CAPACITOR_I30_1
R18  RESISTOR  4.7KOHM 1%  pkg SMC_0402R_H016  page 24 : 1 = XP5R0V_FT4232 ; 2 = FT_USB_DETECT
R19  RESISTOR  10KOHM 1%  pkg SMC_0402R_H016  page 16 : 1 = XP3R3V_FPGA ; 2 = EEPROM_SCL
R20  RESISTOR  4.7KOHM 1%  pkg SMC_0402R_H016  page 17 : 1 = XP3R3V_FPGA ; 2 = LM75B_I2C_SDA
R21  RESISTOR  4.7KOHM 1%  pkg SMC_0402R_H016  page 17 : 1 = XP3R3V_FPGA ; 2 = LM75B_I2C_SCL
R22  RESISTOR  0OHM -  pkg SMC_0402R_H016  page 9 : 1 = CARD_PRESENT ; 2 = UNNAMED_3_CONN64PGF_I61_PRSNT21
R23  RESISTOR  0OHM -  pkg SMC_0402R_H016  page 9 : 1 = CARD_PRESENT ; 2 = UNNAMED_3_CONN64PGF_I61_PRSNT22
R24  RESISTOR  4.7KOHM 1%  pkg SMC_0402R_H016  page 16 : 1 = SEC_EEPROM_WP ; 2 = SG
R25  RESISTOR  4.7KOHM 1%  pkg SMC_0402R_H016  page 9 : 1 = XP3R3V_FPGA ; 2 = UNNAMED_3_G2201019801_I100_EN
R26  RESISTOR  33OHM 1%  pkg SMC_0402R_H016  page 16 : 1 = PCIE_SMDAT ; 2 = R_PCA9546_I2C_SDA
R27  RESISTOR  33OHM 1%  pkg SMC_0402R_H016  page 16 : 1 = PCIE_SMCLK ; 2 = R_PCA9546_I2C_SCL
R28  RESISTOR  0OHM -  pkg SMC_0402R_H016  page 9 : 1 = PCIE_CONN_TCK ; 2 = FPGA_TCK
R29  RESISTOR  100KOHM 1%  pkg SMC_0402R_H016  page 32 : 1 = XP5R0V_RT ; 2 = XP5R0V_AGND
R30  RESISTOR  2.2KOHM 1%  pkg SMC_0402R_H016  page 32 : 1 = XP5R0V_COMP ; 2 = UNNAMED_516_CAPACITOR_I13_1
R31  RESISTOR  0OHM -  pkg SMC_0402R_H016  page 32 : 1 = XP5R0V_BT ; 2 = UNNAMED_516_CAPACITOR_I27_1
R32  RESISTOR  3.24KOHM 1%  pkg SMC_0402R_H014  page 32 : 1 = XP5R0V_FB_R_TO_AGND ; 2 = XP5R0V_AGND
R33  RESISTOR  2.2OHM 1%  pkg SMC_0805R_H026  page 32 : 1 = UNNAMED_516_CAPACITOR_I37_2 ; 2 = SG
R34  RESISTOR  24KOHM 1%  pkg SMC_0402R_H016  page 32 : 1 = UNNAMED_516_CAPACITOR_I29_1 ; 2 = XP5R0V_FB_R_TO_AGND
R35  RESISTOR  100KOHM 1%  pkg SMC_0402R_H016  page 28 : 1 = XP3R3V_RT ; 2 = XP3R3V_AGND
R36  RESISTOR  10KOHM 1%  pkg SMC_0402R_H016  page 28 : 1 = XP3R3V_COMP ; 2 = UNNAMED_517_CAPACITOR_I17_1
R37  RESISTOR  0OHM -  pkg SMC_0402R_H016  page 28 : 1 = XP3R3V_BT ; 2 = UNNAMED_517_CAPACITOR_I27_1
R38  RESISTOR  4.42KOHM 1%  pkg SMC_0402R_H016  page 28 : 1 = XP3R3V_FB_R_TO_AGND ; 2 = XP3R3V_AGND
R39  RESISTOR  2.2OHM 1%  pkg SMC_0805R_H026  page 28 : 1 = UNNAMED_517_CAPACITOR_I29_2 ; 2 = SG
R40  RESISTOR  20KOHM 1%  pkg SMC_0402R_H016  page 28 : 1 = UNNAMED_517_CAPACITOR_I30_1 ; 2 = XP3R3V_FB_R_TO_AGND
R41  RESISTOR  0OHM -  pkg SMC_0402R_H016  page 9 : 1 = PCIE_CONN_TDI ; 2 = FPGA_TDI
R42  RESISTOR  0OHM -  pkg SMC_0402R_H016  page 9 : 1 = PCIE_CONN_TDO ; 2 = FPGA_TDO
R43  RESISTOR  0OHM -  pkg SMC_0402R_H016  page 9 : 1 = PCIE_CONN_TMS ; 2 = FPGA_TMS
R44  RESISTOR  4.7KOHM 1%  pkg SMC_0402R_H016  page 21 : 1 = XP5R0V_MAC ; 2 = UNNAMED_527_POWERMOS3PNCHV1_I23
R45  RESISTOR  33OHM 1%  pkg SMC_0402R_H016  page 16 : 1 = EEPROM_SDA ; 2 = SEC_EEPROM_SDA
R46  RESISTOR  26.7K 1%  pkg SMC_0402R_H016  page 27 : 1 = SG ; 2 = XP12R0V_A_ISET
R47  RESISTOR  10KOHM 1%  pkg SMC_0402R_H016  page 32 : 1 = XP3R3V ; 2 = XP5R0V_PG
R48  RESISTOR  5.1KOHM 1%  pkg SMC_0402R_H016  page 32 : 1 = R_XP5R0V_EN ; 2 = SG
R49  RESISTOR  10KOHM 1%  pkg SMC_0402R_H016  page 32 : 1 = VIN_XP5R0V ; 2 = R_XP5R0V_EN
R50  RESISTOR  0OHM -  pkg SMC_0603R_H024  page 32 : 1 = XP5R0V_AGND ; 2 = XP5R0V_FB_R_TO_AGND
R51  RESISTOR  10KOHM 1%  pkg SMC_0402R_H016  page 28 : 1 = XP3R3V ; 2 = R_XP3R3V_PG
R52  RESISTOR  5.1KOHM 1%  pkg SMC_0402R_H016  page 28 : 1 = XP3R3V_EN ; 2 = SG
R53  RESISTOR  30KOHM 0.1%  pkg SMC_0402R_H016  page 28 : 1 = VIN_XP3R3 ; 2 = XP3R3V_EN
R54  RESISTOR  0OHM -  pkg SMC_0603R_H024  page 28 : 1 = XP3R3V_AGND ; 2 = XP3R3V_FB_R_TO_AGND
R55  RESISTOR  4.7KOHM 1%  pkg SMC_0402R_H016  page 9 : 1 = PCIE_CONN_PERST_N ; 2 = SG
R56  RESISTOR  4.7KOHM 1%  pkg SMC_0402R_H016  page 9 : 1 = XP3R3V ; 2 = PCIE_CONN_PERST_N
R57  RESISTOR  33OHM 1%  pkg SMC_0402R_H016  page 9 : 1 = BF_PCIE_PERST_N ; 2 = PCIE_PERST_N
R58  RESISTOR  33OHM 1%  pkg SMC_0402R_H016  page 16 : 1 = UNNAMED_5_CONNHDR2X2MSSMT_I126_ ; 2 = R_PCA9546_I2C_SDA
R59  RESISTOR  33OHM 1%  pkg SMC_0402R_H016  page 16 : 1 = UNNAMED_5_CONNHDR2X2MSSMT_I12_1 ; 2 = R_PCA9546_I2C_SCL
R60  RESISTOR  33OHM 1%  pkg SMC_0402R_H016  page 16 : 1 = FPGA_OUT_PCA9546_RST_N ; 2 = PCA9546_RST_N
R61  RESISTOR  0OHM -  pkg SMC_0402R_H016  page 16 : 1 = VDD_PCA9546A ; 2 = XP2R5V_FPGA
R62  RESISTOR  0OHM -  pkg SMC_0402R_H016  page 16 : 1 = VDD_PCA9546A ; 2 = XP3R3V_FPGA
R63  RESISTOR  4.7KOHM 1%  pkg SMC_0402R_H016  page 9 : 1 = XP3R3V_FPGA ; 2 = PCIE_PERST_N
R64  RESISTOR  4.7KOHM 1%  pkg SMC_0402R_H016  page 18 : 1 = XP3R3V_FPGA ; 2 = SHT3X_I2C_SDA
R65  RESISTOR  4.7KOHM 1%  pkg SMC_0402R_H016  page 18 : 1 = XP3R3V_FPGA ; 2 = SHT3X_I2C_SCL
R66  RESISTOR  33OHM 1%  pkg SMC_0402R_H016  page 18 : 1 = SHT3X_I2C_SDA ; 2 = R_SHT3X_I2C_SDA
R67  RESISTOR  33OHM 1%  pkg SMC_0402R_H016  page 18 : 1 = SHT3X_I2C_SCL ; 2 = R_SHT3X_I2C_SCL
R68  RESISTOR  4.7KOHM 1%  pkg SMC_0402R_H016  page 18 : 1 = XP3R3V_FPGA ; 2 = SHT3X_ADDR
R69  RESISTOR  1KOHM 1%  pkg SMC_0402R_H016  page 18 : 1 = SHT3X_ADDR ; 2 = SG
R70  RESISTOR  4.7KOHM 1%  pkg SMC_0402R_H016  page 19 : 1 = XP1R8V_ICP10100 ; 2 = BF_ICP10100_I2C_SDA
R71  RESISTOR  4.7KOHM 1%  pkg SMC_0402R_H016  page 19 : 1 = XP1R8V_ICP10100 ; 2 = BF_ICP10100_I2C_SCL
R72  RESISTOR  33OHM 1%  pkg SMC_0402R_H016  page 19 : 1 = BF_ICP10100_I2C_SDA ; 2 = R_ICP10100_I2C_SDA
R73  RESISTOR  33OHM 1%  pkg SMC_0402R_H016  page 19 : 1 = BF_ICP10100_I2C_SCL ; 2 = R_ICP10100_I2C_SCL
R74  RESISTOR  4.7KOHM 1%  pkg SMC_0402R_H016  page 20 : 1 = XP3R3V_FPGA ; 2 = BNO080_I2C_SDA
R75  RESISTOR  4.7KOHM 1%  pkg SMC_0402R_H016  page 20 : 1 = XP3R3V_FPGA ; 2 = BNO080_I2C_SCL
R76  RESISTOR  33OHM 1%  pkg SMC_0402R_H016  page 20 : 1 = BNO080_I2C_SDA ; 2 = R_BNO080_I2C_SDA
R77  RESISTOR  33OHM 1%  pkg SMC_0402R_H016  page 20 : 1 = BNO080_I2C_SCL ; 2 = R_BNO080_I2C_SCL
R78  RESISTOR  33OHM 1%  pkg SMC_0402R_H016  page 20 : 1 = R_BNO080_RST_N ; 2 = FPGA_OUT_BNO080_RST_N
R79  RESISTOR  33OHM 1%  pkg SMC_0402R_H016  page 20 : 1 = FPGA_IN_BNO080_INT_N ; 2 = R_BNO080_INT_N
R80  RESISTOR  33OHM 1%  pkg SMC_0402R_H016  page 20 : 1 = FPGA_OUT_BNO080_BOOT_N ; 2 = R_BNO080_BOOT_N
R81  RESISTOR  33OHM 1%  pkg SMC_0402R_H016  page 21 : 1 = R_MAC_UART_RX_FPGA_TX ; 2 = DBG_UART_MAC_RX
R82  RESISTOR  33OHM 1%  pkg SMC_0402R_H016  page 21 : 1 = R_MAC_UART_TX_FPGA_RX ; 2 = DBG_UART_MAC_TX
R83  RESISTOR  0OHM -  pkg SMC_0402R_H016  page 21 : 1 = FPGA_OUT_MAC_PPS_IN1P ; 2 = R_MAC_PPS_IN1P
R84  RESISTOR  0OHM -  pkg SMC_0402R_H016  page 21 : 1 = FPGA_OUT_MAC_PPS_IN1N ; 2 = R_MAC_PPS_IN1N
R85  RESISTOR  0OHM -  pkg SMC_0402R_H016  page 21 : 1 = FPGA_OUT_MAC_PPS_IN0P ; 2 = R_MAC_PPS_IN0P
R86  RESISTOR  0OHM -  pkg SMC_0402R_H016  page 21 : 1 = FPGA_OUT_MAC_PPS_IN0N ; 2 = R_MAC_PPS_IN0N
R87  RESISTOR  0OHM -  pkg SMC_0402R_H016  page 21 : 1 = FPGA_IN_MAC_PPS_OUTP ; 2 = R_MAC_PPS_OUTP
R88  RESISTOR  0OHM -  pkg SMC_0402R_H016  page 21 : 1 = FPGA_IN_MAC_PPS_OUTN ; 2 = R_MAC_PPS_OUTN
R89  RESISTOR  100OHM 1%  pkg SMC_0402R_H016  page 21 : 1 = R_MAC_PPS_IN1P ; 2 = R_MAC_PPS_IN1N
R90  RESISTOR  100OHM 1%  pkg SMC_0402R_H016  page 21 : 1 = R_MAC_PPS_IN0N ; 2 = R_MAC_PPS_IN0P
R91  RESISTOR  33OHM 1%  pkg SMC_0402R_H016  page 21 : 1 = ANALOG_TUNING_IN ; 2 = SMA_ANALOG_TUNING_IN
R92  RESISTOR  100OHM 1%  pkg SMC_0402R_H016  page 21 : 1 = R_MAC_10MHZ_RF_OUT ; 2 = FPGA_IN_MAC_10MHZ_OUT
R93  RESISTOR  33OHM 1%  pkg SMC_0402R_H016  page 21 : 1 = R_MAC_BITEOUT ; 2 = FPGA_IN_MAC_BITEOUT
R94  RESISTOR  33OHM 1%  pkg SMC_0402R_H016  page 21 : 1 = R_MAC_UART_TX_FPGA_RX ; 2 = UART_MAC_TX_FPGA_RX
R95  RESISTOR  33OHM 1%  pkg SMC_0402R_H016  page 21 : 1 = R_MAC_UART_RX_FPGA_TX ; 2 = UART_MAC_RX_FPGA_TX
R96  RESISTOR  33OHM 1%  pkg SMC_0402R_H016  page 21 : 1 = MAC_ALARM ; 2 = FPGA_IN_MAC_ALARM_OUT_N
R97  RESISTOR  0OHM -  pkg SMC_0402R_H016  page 21 : 1 = R_MAC_USB_DP ; 2 = MUX_USB_DP
R98  RESISTOR  0OHM -  pkg SMC_0402R_H016  page 21 : 1 = R_MAC_USB_DM ; 2 = MUX_USB_DM
R99  RESISTOR  4.7KOHM 1%  pkg SMC_0402R_H016  page 21 : 1 = FPGA_OUT_MACUSBPOWER_EN ; 2 = SG
R100  RESISTOR  33OHM 1%  pkg SMC_0402R_H016  page 21 : 1 = FPGA_OUT_MACUSBPOWER_EN ; 2 = USB_PWR_EN
R101  RESISTOR  1KOHM 1%  pkg SMC_0402R_H016  page 21 : 1 = XP5R0V_USB_CONN ; 2 = XP5R0V_USB_CONN_DET
R102  RESISTOR  1KOHM 1%  pkg SMC_0402R_H016  page 21 : 1 = XP5R0V_USB_CONN_DET ; 2 = UNNAMED_527_RESISTOR_I201_2
R103  RESISTOR  1KOHM 1%  pkg SMC_0402R_H016  page 21 : 1 = UNNAMED_527_RESISTOR_I201_2 ; 2 = SG
R104  RESISTOR  4.7KOHM 1%  pkg SMC_0402R_H016  page 21 : 1 = UNNAMED_527_RESISTOR_I126_1 ; 2 = SG
R105  RESISTOR  0OHM -  pkg SMC_0402R_H016  page 21 : 1 = MUX_USB_DM ; 2 = MAC_USB_DM
R106  RESISTOR  0OHM -  pkg SMC_0402R_H016  page 21 : 1 = MUX_USB_DP ; 2 = MAC_USB_DP
R107  RESISTOR  4.7KOHM 1%  pkg SMC_0402R_H016  page 21 : 1 = XP3R3V_FPGA ; 2 = FPGA_IN_MAC_USB_OC_N
R108  RESISTOR  100OHM 1%  pkg SMC_0402R_H016  page 26 : 1 = UNNAMED_14_OPTICAL_I141_A ; 2 = UNNAMED_14_RESISTOR_I58_2
R109  RESISTOR  33OHM 1%  pkg SMC_0402R_H016  page 22 : 1 = UART_GPS_TX_FPGA_RX ; 2 = GPS_UART_TXD
R110  RESISTOR  33OHM 1%  pkg SMC_0402R_H016  page 22 : 1 = UART_GPS_RX_FPGA_TX ; 2 = GPS_UART_RXD
R111  RESISTOR  33OHM 1%  pkg SMC_0402R_H016  page 22 : 1 = FPGA_IN_GPSTP2_OUT ; 2 = GPSTP2_OUT
R112  RESISTOR  33OHM 1%  pkg SMC_0402R_H016  page 22 : 1 = DBG_UART_GPS_TXD ; 2 = GPS_UART_TXD
R113  RESISTOR  33OHM 1%  pkg SMC_0402R_H016  page 22 : 1 = DBG_UART_GPS_RXD ; 2 = GPS_UART_RXD
R114  RESISTOR  4.7KOHM 1%  pkg SMC_0402R_H016  page 22 : 1 = GPS_RST_N ; 2 = SG
R115  RESISTOR  4.7KOHM 1%  pkg SMC_0402R_H016  page 22 : 1 = XP3R3V_GPS ; 2 = GPS_RST_N
R116  RESISTOR  33OHM 1%  pkg SMC_0402R_H016  page 22 : 1 = GPS_RST_N ; 2 = FPGA_OUT_GPS_RST_N
R117  RESISTOR  33OHM 1%  pkg SMC_0402R_H016  page 22 : 1 = GPSTP1_OUT ; 2 = FPGA_IN_GPSTP1_OUT
R118  RESISTOR  330OHM 1%  pkg SMC_0402R_H016  page 26 : 1 = UNNAMED_14_OPTICAL_I191_A ; 2 = XP3R3V_PCIE
R119  RESISTOR  330OHM 1%  pkg SMC_0402R_H016  page 26 : 1 = UNNAMED_14_OPTICAL_I194_A ; 2 = XP3R3V_AUX_PCIE
R120  RESISTOR  100OHM 1%  pkg SMC_0402R_H016  page 23 : 1 = ANT1_OUT ; 2 = UNNAMED_12_74HCT2G125DPTSSOP8_6
R121  RESISTOR  100OHM 1%  pkg SMC_0402R_H016  page 23 : 1 = ANT2_OUT ; 2 = UNNAMED_12_74HCT2G125DPTSSOP8_9
R122  RESISTOR  49.9OHM 1%  pkg SMC_0402R_H016  page 23 : 1 = BF_SMA3_SIG_IO_CONN ; 2 = SMA3_SIG_IO_CONN
R123  RESISTOR  49.9OHM 1%  pkg SMC_0402R_H016  page 23 : 1 = BF_SMA4_SIG_IO_CONN ; 2 = SMA4_SIG_IO_CONN
R124  RESISTOR  100OHM 1%  pkg SMC_0402R_H016  page 26 : 1 = FPGA_OUT_SMA1_LED_BLUE_N ; 2 = UNNAMED_14_LED4PV14_I265_1
R125  RESISTOR  100OHM 1%  pkg SMC_0402R_H016  page 26 : 1 = FPGA_OUT_SMA1_LED_GREEN_N ; 2 = UNNAMED_14_LED4PV14_I265_4
R126  RESISTOR  49.9OHM 1%  pkg SMC_0402R_H016  page 23 : 1 = BF_SMA2_SIG_IO_CONN ; 2 = SMA2_SIG_IO_CONN
R127  RESISTOR  49.9OHM 1%  pkg SMC_0402R_H016  page 23 : 1 = BF_SMA1_SIG_IO_CONN ; 2 = SMA1_SIG_IO_CONN
R128  RESISTOR  0OHM -  pkg SMC_0402R_H016  page 24 : 1 = FT_USB_DM ; 2 = R_FT_USB_DM
R129  RESISTOR  0OHM -  pkg SMC_0402R_H016  page 24 : 1 = FT_USB_DP ; 2 = R_FT_USB_DP
R130  RESISTOR  10KOHM 1%  pkg SMC_0402R_H016  page 24 : 1 = FT_USB_DETECT ; 2 = SG
R131  RESISTOR  100OHM 1%  pkg SMC_0402R_H016  page 24 : 1 = R_FT4232_CHD_TX ; 2 = FT4232_CHD_TX
R132  RESISTOR  100OHM 1%  pkg SMC_0402R_H016  page 24 : 1 = R_FT4232_CHD_RX ; 2 = FT4232_CHD_RX
R133  RESISTOR  33OHM 1%  pkg SMC_0402R_H016  page 10 : 1 = XP3R3V_FPGA ; 2 = UNNAMED_127_G2001028301_I427_4
R134  RESISTOR  33OHM 1%  pkg SMC_0402R_H016  page 10 : 1 = FT4232_FPGA_TCK ; 2 = FPGA_TCK
R135  RESISTOR  0OHM -  pkg SMC_0402R_H016  page 10 : 1 = FT4232_FPGA_TDO ; 2 = FPGA_TDO
R136  RESISTOR  33OHM 1%  pkg SMC_0402R_H016  page 10 : 1 = FT4232_FPGA_TMS ; 2 = FPGA_TMS
R137  RESISTOR  33OHM 1%  pkg SMC_0402R_H016  page 10 : 1 = FT4232_FPGA_TDI ; 2 = FPGA_TDI
R138  RESISTOR  330OHM 1%  pkg SMC_0402R_H016  page 26 : 1 = UNNAMED_14_OPTICAL_I140_A ; 2 = XP3R3V_FPGA
R139  RESISTOR  33OHM 1%  pkg SMC_0402R_H016  page 26 : 1 = UNNAMED_14_RESISTOR_I58_2 ; 2 = XP2R5V_FPGA
R140  RESISTOR  0OHM -  pkg SMC_0402R_H016  page 30 : 1 = XP1R0V_FPGA_PG ; 2 = XP1R2V_EN_R
R141  RESISTOR  0OHM -  pkg SMC_0402R_H016  page 30 : 1 = XP1R2V_FPGA_PG ; 2 = XP1R8V_EN_R
R142  RESISTOR  100OHM 1%  pkg SMC_0402R_H016  page 32 : 1 = XP1R8V_FPGA_PG ; 2 = R_XP5R0V_EN
R143  RESISTOR  33OHM 1%  pkg SMC_0402R_H016  page 31 : 1 = FPGA_CFG_INIT_N ; 2 = UNNAMED_515_NCP45560IMNTWGHDFN1
R144  RESISTOR  33OHM 1%  pkg SMC_0402R_H016  page 16 : 1 = PCA9546_I2C_SDA ; 2 = R_PCA9546_I2C_SDA
R145  RESISTOR  33OHM 1%  pkg SMC_0402R_H016  page 16 : 1 = PCA9546_I2C_SCL ; 2 = R_PCA9546_I2C_SCL
R146  RESISTOR  10KOHM 1%  pkg SMC_0402R_H016  page 16 : 1 = XP3R3V_FPGA ; 2 = PCA9546_RST_N
R147  RESISTOR  10KOHM 1%  pkg SMC_0402R_H016  page 16 : 1 = XP3R3V_FPGA ; 2 = R_PCA9546_I2C_SDA
R148  RESISTOR  10KOHM 1%  pkg SMC_0402R_H016  page 16 : 1 = XP3R3V_FPGA ; 2 = R_PCA9546_I2C_SCL
R149  RESISTOR  4.7KOHM 1%  pkg SMC_0402R_H016  page 16 : 1 = XP3R3V_FPGA ; 2 = UNNAMED_5_PCA9546APWTSSOP16_I33
R150  RESISTOR  4.7KOHM 1%  pkg SMC_0402R_H016  page 16 : 1 = XP3R3V_FPGA ; 2 = UNNAMED_5_PCA9546APWTSSOP16_I_1
R151  RESISTOR  4.7KOHM 1%  pkg SMC_0402R_H016  page 16 : 1 = XP3R3V_FPGA ; 2 = UNNAMED_5_PCA9546APWTSSOP16_I_2
R152  RESISTOR  4.7KOHM 1%  pkg SMC_0402R_H016  page 16 : 1 = SG ; 2 = UNNAMED_5_PCA9546APWTSSOP16_I33
R153  RESISTOR  4.7KOHM 1%  pkg SMC_0402R_H016  page 16 : 1 = SG ; 2 = UNNAMED_5_PCA9546APWTSSOP16_I_1
R154  RESISTOR  4.7KOHM 1%  pkg SMC_0402R_H016  page 16 : 1 = SG ; 2 = UNNAMED_5_PCA9546APWTSSOP16_I_2
R155  RESISTOR  4.7KOHM 1%  pkg SMC_0402R_H016  page 16 : 1 = SG ; 2 = PCA9546_RST_N
R156  RESISTOR  100OHM 1%  pkg SMC_0402R_H016  page 23 : 1 = ANT3_OUT ; 2 = UNNAMED_12_74HCT2G125DPTSSOP8_I
R157  RESISTOR  100OHM 1%  pkg SMC_0402R_H016  page 23 : 1 = ANT4_OUT ; 2 = UNNAMED_12_74HCT2G125DPTSSOP8_3
R158  RESISTOR  4.7KOHM 1%  pkg SMC_0402R_H016  page 16 : 1 = XP3R3V_FPGA ; 2 = UNNAMED_5_24LC16BTISTTSSOP8_I15
R159  RESISTOR  4.7KOHM 1%  pkg SMC_0402R_H016  page 16 : 1 = UNNAMED_5_24LC16BTISTTSSOP8_I15 ; 2 = SG
R160  RESISTOR  4.7KOHM 1%  pkg SMC_0402R_H016  page 16 : 1 = XP3R3V_FPGA ; 2 = UNNAMED_5_24LC16BTISTTSSOP8_I_1
R161  RESISTOR  4.7KOHM 1%  pkg SMC_0402R_H016  page 16 : 1 = UNNAMED_5_24LC16BTISTTSSOP8_I_1 ; 2 = SG
R162  RESISTOR  4.7KOHM 1%  pkg SMC_0402R_H016  page 16 : 1 = XP3R3V_FPGA ; 2 = UNNAMED_5_24LC16BTISTTSSOP8_I_2
R163  RESISTOR  4.7KOHM 1%  pkg SMC_0402R_H016  page 16 : 1 = UNNAMED_5_24LC16BTISTTSSOP8_I_2 ; 2 = SG
R164  RESISTOR  100KOHM 1%  pkg SMC_0402R_H016  page 9 : 1 = XP3R3V_FPGA ; 2 = UNNAMED_3_RESISTOR_I151_2
